FILE_TYPE = CONNECTIVITY;
{Allegro Design Entry HDL 16.6-p007 (v16-6-112F) 10/10/2012}
"PAGE_NUMBER" = 54;
0"NC";
1"M_F_DQS_DP<17:0>";
2"M_F_DQS_DN<17:0>";
3"M_F_MA<17:0>";
4"M_F_DQ<63:0>";
5"M_F_CLK_DN<3:0>";
6"M_F_CLK_DP<3:0>";
7"M_F_CKE<3:0>";
8"M_F_CS_N<7:0>";
9"M_F_ODT<3:0>";
10"M_F_BA<1:0>";
11"M_F_BG<1:0>";
12"M_F_ECC<7:0>";
13"PVDDQ_DEF\g";
14"PVTT_DEF\g";
15"GND\g";
16"GND\g";
17"PVPP_DEF\g";
18"PVPP_DEF\g";
19"GND\g";
20"P12V_NVDIMM_DEF\g";
21"GND\g";
22"M_F_VREF";
23"TP_CH_F_DIMM_F1_RFU_2";
24"TP_CH_F_DIMM_F1_RFU_0";
25"TP_CH_F_DIMM_F1_RFU_1";
26"SMB_DDR_DEF_VPP_SCL";
27"SMB_DDR_DEF_VPP_SDA";
28"FM_ADR_COMPLETE_DEF_N";
29"FM_DIMM_EVENT_COD_N";
30"M_F_PAR";
31"M_DEF_RST_N";
32"M_F_BA<1>";
33"M_F_CS_N<7>";
34"M_F_CS_N<6>";
35"M_F_CS_N<5>";
36"M_F_MA<0>";
37"M_F_MA<1>";
38"M_F_MA<3>";
39"M_F_ECC<6>";
40"M_F_ECC<5>";
41"M_F_ECC<4>";
42"M_F_ECC<3>";
43"M_F_ECC<2>";
44"M_F_ECC<1>";
45"M_F_ECC<0>";
46"M_F_CKE<3>";
47"M_F_BG<0>";
48"M_F_BG<1>";
49"M_F_BA<0>";
50"M_F_MA<2>";
51"M_F_ECC<7>";
52"M_F_ODT<2>";
53"M_F_ODT<3>";
54"M_F_CS_N<4>";
55"M_F_CKE<2>";
56"M_F_CLK_DP<2>";
57"M_F_CLK_DP<3>";
58"M_F_CLK_DN<3>";
59"M_F_CLK_DN<2>";
60"M_F_ACT_N";
61"M_F_ALERT_N";
62"M_F_C<2>";
63"M_F_DQ<8>";
64"M_F_DQ<7>";
65"M_F_DQ<6>";
66"M_F_DQ<1>";
67"M_F_DQ<0>";
68"M_F_DQ<2>";
69"M_F_DQ<3>";
70"M_F_DQ<4>";
71"M_F_DQ<5>";
72"M_F_DQ<19>";
73"M_F_DQ<18>";
74"M_F_DQ<16>";
75"M_F_DQ<14>";
76"M_F_DQ<13>";
77"M_F_DQ<12>";
78"M_F_DQ<11>";
79"M_F_DQ<9>";
80"M_F_DQ<15>";
81"M_F_DQ<17>";
82"M_F_DQ<10>";
83"M_F_DQ<29>";
84"M_F_DQ<28>";
85"M_F_DQ<25>";
86"M_F_DQ<24>";
87"M_F_DQ<23>";
88"M_F_DQ<22>";
89"M_F_DQ<21>";
90"M_F_DQ<20>";
91"M_F_DQ<27>";
92"M_F_DQ<26>";
93"M_F_DQ<39>";
94"M_F_DQ<37>";
95"M_F_DQ<34>";
96"M_F_DQ<33>";
97"M_F_DQ<32>";
98"M_F_DQ<31>";
99"M_F_DQ<30>";
100"M_F_DQ<35>";
101"M_F_DQ<36>";
102"M_F_DQ<38>";
103"M_F_DQ<46>";
104"M_F_DQ<45>";
105"M_F_DQ<44>";
106"M_F_DQ<43>";
107"M_F_DQ<42>";
108"M_F_DQ<41>";
109"M_F_DQ<40>";
110"M_F_DQ<49>";
111"M_F_DQ<48>";
112"M_F_DQ<47>";
113"M_F_MA<12>";
114"M_F_MA<13>";
115"M_F_MA<17>";
116"M_F_MA<4>";
117"M_F_MA<5>";
118"M_F_MA<6>";
119"M_F_MA<7>";
120"M_F_MA<8>";
121"M_F_MA<9>";
122"M_F_MA<10>";
123"M_F_MA<11>";
124"M_F_MA<14>";
125"M_F_MA<15>";
126"M_F_MA<16>";
127"M_F_DQ<60>";
128"M_F_DQ<59>";
129"M_F_DQ<56>";
130"M_F_DQ<55>";
131"M_F_DQ<57>";
132"M_F_DQ<58>";
133"M_F_DQ<54>";
134"M_F_DQ<53>";
135"M_F_DQ<52>";
136"M_F_DQ<51>";
137"M_F_DQ<50>";
138"M_F_DQ<63>";
139"M_F_DQ<62>";
140"M_F_DQ<61>";
141"M_F_DQS_DN<0>";
142"M_F_DQS_DP<0>";
143"M_F_DQS_DN<1>";
144"M_F_DQS_DP<1>";
145"M_F_DQS_DN<2>";
146"M_F_DQS_DP<2>";
147"M_F_DQS_DN<3>";
148"M_F_DQS_DP<3>";
149"M_F_DQS_DN<4>";
150"M_F_DQS_DP<4>";
151"M_F_DQS_DN<5>";
152"M_F_DQS_DP<5>";
153"M_F_DQS_DN<6>";
154"M_F_DQS_DP<6>";
155"M_F_DQS_DN<10>";
156"M_F_DQS_DP<10>";
157"M_F_DQS_DN<11>";
158"M_F_DQS_DP<11>";
159"M_F_DQS_DN<12>";
160"M_F_DQS_DP<12>";
161"M_F_DQS_DN<13>";
162"M_F_DQS_DP<13>";
163"M_F_DQS_DN<14>";
164"M_F_DQS_DP<14>";
165"M_F_DQS_DN<15>";
166"M_F_DQS_DP<15>";
167"M_F_DQS_DN<16>";
168"M_F_DQS_DP<16>";
169"M_F_DQS_DN<17>";
170"M_F_DQS_DN<7>";
171"M_F_DQS_DP<7>";
172"M_F_DQS_DN<8>";
173"M_F_DQS_DP<8>";
174"M_F_DQS_DN<9>";
175"M_F_DQS_DP<9>";
176"M_F_DQS_DP<17>";
%"TAP"
"6","(700,4850)","2","mstr_standard","I10";
;
HDL_TAP"TRUE"
BODY_TYPE"PLUMBING"
CDS_LIB"mstr_standard";
"B \NAC \NWC"1;
"S \NAC"
BN"14"164;
%"TAP"
"6","(-1650,2050)","2","mstr_standard","I100";
;
HDL_TAP"TRUE"
BODY_TYPE"PLUMBING"
CDS_LIB"mstr_standard";
"B \NAC \NWC"4;
"S \NAC"
BN"9"79;
%"TAP"
"6","(-1650,2100)","2","mstr_standard","I101";
;
HDL_TAP"TRUE"
BODY_TYPE"PLUMBING"
CDS_LIB"mstr_standard";
"B \NAC \NWC"4;
"S \NAC"
BN"10"82;
%"TAP"
"6","(-1650,1800)","2","mstr_standard","I102";
;
HDL_TAP"TRUE"
BODY_TYPE"PLUMBING"
CDS_LIB"mstr_standard";
"B \NAC \NWC"4;
"S \NAC"
BN"4"70;
%"TAP"
"6","(-1650,1750)","2","mstr_standard","I103";
;
HDL_TAP"TRUE"
BODY_TYPE"PLUMBING"
CDS_LIB"mstr_standard";
"B \NAC \NWC"4;
"S \NAC"
BN"3"69;
%"TAP"
"6","(-1650,1850)","2","mstr_standard","I104";
;
HDL_TAP"TRUE"
BODY_TYPE"PLUMBING"
CDS_LIB"mstr_standard";
"B \NAC \NWC"4;
"S \NAC"
BN"5"71;
%"TAP"
"6","(-1650,1900)","2","mstr_standard","I105";
;
HDL_TAP"TRUE"
BODY_TYPE"PLUMBING"
CDS_LIB"mstr_standard";
"B \NAC \NWC"4;
"S \NAC"
BN"6"65;
%"TAP"
"6","(-1650,2000)","2","mstr_standard","I106";
;
HDL_TAP"TRUE"
BODY_TYPE"PLUMBING"
CDS_LIB"mstr_standard";
"B \NAC \NWC"4;
"S \NAC"
BN"8"63;
%"TAP"
"6","(-1650,1950)","2","mstr_standard","I107";
;
HDL_TAP"TRUE"
BODY_TYPE"PLUMBING"
CDS_LIB"mstr_standard";
"B \NAC \NWC"4;
"S \NAC"
BN"7"64;
%"TAP"
"6","(-1650,1600)","2","mstr_standard","I108";
;
HDL_TAP"TRUE"
BODY_TYPE"PLUMBING"
CDS_LIB"mstr_standard";
"B \NAC \NWC"4;
"S \NAC"
BN"0"67;
%"TAP"
"6","(-1650,1700)","2","mstr_standard","I109";
;
HDL_TAP"TRUE"
BODY_TYPE"PLUMBING"
CDS_LIB"mstr_standard";
"B \NAC \NWC"4;
"S \NAC"
BN"2"68;
%"TAP"
"6","(700,4950)","2","mstr_standard","I11";
;
HDL_TAP"TRUE"
BODY_TYPE"PLUMBING"
CDS_LIB"mstr_standard";
"B \NAC \NWC"1;
"S \NAC"
BN"15"166;
%"TAP"
"6","(-1650,1650)","2","mstr_standard","I110";
;
HDL_TAP"TRUE"
BODY_TYPE"PLUMBING"
CDS_LIB"mstr_standard";
"B \NAC \NWC"4;
"S \NAC"
BN"1"66;
%"SCONN288_H44441003"
"1","(-2400,3100)","0","mstr_sconn","I111";
;
CDS_SEC"1"
ROOM"DDR4_CH_F1"
CDS_LOCATION"J6L1"
SEC"1"
SEC_TYPE"PIP"
CDS_LIB"mstr_sconn"
BOM_COST"MEM"
PACK_TYPE"PIP"
MATERIAL"SCONN"
PART_NUMBER"H44441-003"
LOCATION"J6L1";
"DQ<63>"
$PN"280"138;
"BA<1>"
$PN"224"32;
"CK1N"
$PN"219"58;
"CK0P"
$PN"74"56;
"S3_N_C<1>"
$PN"237"33;
"S2_N_C<0>"
$PN"93"34;
"S1_N"
$PN"89"35;
"DQ<29>"
$PN"181"83;
"DQ<28>"
$PN"36"84;
"C<2>"
$PN"235"62;
"A0"
$PN"79"36;
"A1"
$PN"72"37;
"A12"
$PN"65"113;
"A13"
$PN"232"114;
"A17"
$PN"234"115;
"A3"
$PN"71"38;
"A4"
$PN"214"116;
"A5"
$PN"213"117;
"A6"
$PN"69"118;
"A7"
$PN"211"119;
"A8"
$PN"68"120;
"A9"
$PN"66"121;
"CB<6>"
$PN"54"39;
"CB<5>"
$PN"192"40;
"CB<4>"
$PN"47"41;
"CB<3>"
$PN"201"42;
"CB<2>"
$PN"56"43;
"CB<1>"
$PN"194"44;
"CB<0>"
$PN"49"45;
"CK0N"
$PN"75"59;
"CKE<1>"
$PN"203"46;
"DQ<62>"
$PN"135"139;
"DQ<61>"
$PN"273"140;
"DQ<60>"
$PN"128"127;
"DQ<59>"
$PN"282"128;
"DQ<56>"
$PN"130"129;
"DQ<55>"
$PN"269"130;
"DQ<46>"
$PN"113"103;
"DQ<45>"
$PN"251"104;
"DQ<44>"
$PN"106"105;
"DQ<43>"
$PN"260"106;
"DQ<42>"
$PN"115"107;
"DQ<41>"
$PN"253"108;
"DQ<40>"
$PN"108"109;
"DQ<39>"
$PN"247"93;
"DQ<37>"
$PN"240"94;
"DQ<34>"
$PN"104"95;
"DQ<33>"
$PN"242"96;
"DQ<32>"
$PN"97"97;
"DQ<31>"
$PN"188"98;
"DQ<30>"
$PN"43"99;
"DQ<25>"
$PN"183"85;
"DQ<24>"
$PN"38"86;
"DQ<23>"
$PN"177"87;
"DQ<22>"
$PN"32"88;
"DQ<21>"
$PN"170"89;
"DQ<20>"
$PN"25"90;
"DQ<19>"
$PN"179"72;
"DQ<18>"
$PN"34"73;
"DQ<16>"
$PN"27"74;
"DQ<14>"
$PN"21"75;
"DQ<13>"
$PN"159"76;
"DQ<12>"
$PN"14"77;
"DQ<11>"
$PN"168"78;
"DQ<10>"
$PN"23"82;
"DQ<9>"
$PN"161"79;
"DQ<8>"
$PN"16"63;
"DQ<7>"
$PN"155"64;
"DQ<6>"
$PN"10"65;
"EVENT_N"
$PN"78"29;
"PAR"
$PN"222"30;
"RESET_N"
$PN"58"31;
"RFU<2>"
$PN"144"23;
"SCL"
$PN"141"26;
"SDA"
$PN"285"27;
"VREFCA"
$PN"146"22;
"CK1P"
$PN"218"57;
"BG<0>"
$PN"63"47;
"BG<1>"
$PN"207"48;
"BA<0>"
$PN"81"49;
"SA<0>"
$PN"139"18;
"VDDSPD"
$PN"284"18;
"SA<2>"
$PN"238"18;
"SA<1>"
$PN"140"19;
"DQ<1>"
$PN"150"66;
"DQ<0>"
$PN"5"67;
"ACT_N"
$PN"62"60;
"ALERT_N"
$PN"208"61;
"A2"
$PN"216"50;
"DQ<35>"
$PN"249"100;
"DQ<36>"
$PN"95"101;
"DQ<38>"
$PN"102"102;
"A10"
$PN"225"122;
"A11"
$PN"210"123;
"A14_WE_N"
$PN"228"124;
"A15_CAS_N"
$PN"86"125;
"A16_RAS_N"
$PN"82"126;
"CB<7>"
$PN"199"51;
"ODT<0>"
$PN"87"52;
"ODT<1>"
$PN"91"53;
"CKE<0>"
$PN"60"55;
"S0_N"
$PN"84"54;
"DQ<27>"
$PN"190"91;
"DQ<26>"
$PN"45"92;
"DQ<15>"
$PN"166"80;
"DQ<17>"
$PN"172"81;
"RFU<0>"
$PN"205"24;
"RFU<1>"
$PN"227"25;
"SAVE_N_NC"
$PN"230"28;
"DQ<57>"
$PN"275"131;
"DQ<58>"
$PN"137"132;
"DQ<54>"
$PN"124"133;
"DQ<53>"
$PN"262"134;
"DQ<52>"
$PN"117"135;
"DQ<51>"
$PN"271"136;
"DQ<50>"
$PN"126"137;
"DQ<49>"
$PN"264"110;
"DQ<48>"
$PN"119"111;
"DQ<47>"
$PN"258"112;
"DQ<2>"
$PN"12"68;
"DQ<3>"
$PN"157"69;
"DQ<4>"
$PN"3"70;
"DQ<5>"
$PN"148"71;
%"TAP"
"6","(-3150,4700)","0","mstr_standard","I112";
;
HDL_TAP"TRUE"
BODY_TYPE"PLUMBING"
CDS_LIB"mstr_standard";
"B \NAC \NWC"3;
"S \NAC"
BN"16"126;
%"TAP"
"6","(-3150,4750)","0","mstr_standard","I113";
;
HDL_TAP"TRUE"
BODY_TYPE"PLUMBING"
CDS_LIB"mstr_standard";
"B \NAC \NWC"3;
"S \NAC"
BN"17"115;
%"TAP"
"6","(-3150,4650)","0","mstr_standard","I114";
;
HDL_TAP"TRUE"
BODY_TYPE"PLUMBING"
CDS_LIB"mstr_standard";
"B \NAC \NWC"3;
"S \NAC"
BN"15"125;
%"TAP"
"6","(-3150,4600)","0","mstr_standard","I115";
;
HDL_TAP"TRUE"
BODY_TYPE"PLUMBING"
CDS_LIB"mstr_standard";
"B \NAC \NWC"3;
"S \NAC"
BN"14"124;
%"TAP"
"6","(-3150,4550)","0","mstr_standard","I116";
;
HDL_TAP"TRUE"
BODY_TYPE"PLUMBING"
CDS_LIB"mstr_standard";
"B \NAC \NWC"3;
"S \NAC"
BN"13"114;
%"TAP"
"6","(-3150,4500)","0","mstr_standard","I117";
;
HDL_TAP"TRUE"
BODY_TYPE"PLUMBING"
CDS_LIB"mstr_standard";
"B \NAC \NWC"3;
"S \NAC"
BN"12"113;
%"TAP"
"6","(-3150,4450)","0","mstr_standard","I118";
;
HDL_TAP"TRUE"
BODY_TYPE"PLUMBING"
CDS_LIB"mstr_standard";
"B \NAC \NWC"3;
"S \NAC"
BN"11"123;
%"TAP"
"6","(-3150,4400)","0","mstr_standard","I119";
;
HDL_TAP"TRUE"
BODY_TYPE"PLUMBING"
CDS_LIB"mstr_standard";
"B \NAC \NWC"3;
"S \NAC"
BN"10"122;
%"TAP"
"6","(700,5050)","2","mstr_standard","I12";
;
HDL_TAP"TRUE"
BODY_TYPE"PLUMBING"
CDS_LIB"mstr_standard";
"B \NAC \NWC"1;
"S \NAC"
BN"16"168;
%"TAP"
"6","(-3150,4350)","0","mstr_standard","I120";
;
HDL_TAP"TRUE"
BODY_TYPE"PLUMBING"
CDS_LIB"mstr_standard";
"B \NAC \NWC"3;
"S \NAC"
BN"9"121;
%"TAP"
"6","(-3150,4300)","0","mstr_standard","I121";
;
HDL_TAP"TRUE"
BODY_TYPE"PLUMBING"
CDS_LIB"mstr_standard";
"B \NAC \NWC"3;
"S \NAC"
BN"8"120;
%"TAP"
"6","(-3150,4250)","0","mstr_standard","I122";
;
HDL_TAP"TRUE"
BODY_TYPE"PLUMBING"
CDS_LIB"mstr_standard";
"B \NAC \NWC"3;
"S \NAC"
BN"7"119;
%"TAP"
"6","(-3150,4200)","0","mstr_standard","I123";
;
HDL_TAP"TRUE"
BODY_TYPE"PLUMBING"
CDS_LIB"mstr_standard";
"B \NAC \NWC"3;
"S \NAC"
BN"6"118;
%"TAP"
"6","(-3150,4150)","0","mstr_standard","I124";
;
HDL_TAP"TRUE"
BODY_TYPE"PLUMBING"
CDS_LIB"mstr_standard";
"B \NAC \NWC"3;
"S \NAC"
BN"5"117;
%"TAP"
"6","(-3150,4100)","0","mstr_standard","I125";
;
HDL_TAP"TRUE"
BODY_TYPE"PLUMBING"
CDS_LIB"mstr_standard";
"B \NAC \NWC"3;
"S \NAC"
BN"4"116;
%"TAP"
"6","(-3150,4000)","0","mstr_standard","I126";
;
HDL_TAP"TRUE"
BODY_TYPE"PLUMBING"
CDS_LIB"mstr_standard";
"B \NAC \NWC"3;
"S \NAC"
BN"2"50;
%"TAP"
"6","(-3150,4050)","0","mstr_standard","I127";
;
HDL_TAP"TRUE"
BODY_TYPE"PLUMBING"
CDS_LIB"mstr_standard";
"B \NAC \NWC"3;
"S \NAC"
BN"3"38;
%"TAP"
"6","(-3150,3950)","0","mstr_standard","I128";
;
HDL_TAP"TRUE"
BODY_TYPE"PLUMBING"
CDS_LIB"mstr_standard";
"B \NAC \NWC"3;
"S \NAC"
BN"1"37;
%"TAP"
"6","(-3150,3900)","0","mstr_standard","I129";
;
HDL_TAP"TRUE"
BODY_TYPE"PLUMBING"
CDS_LIB"mstr_standard";
"B \NAC \NWC"3;
"S \NAC"
BN"0"36;
%"TAP"
"6","(700,4550)","2","mstr_standard","I13";
;
HDL_TAP"TRUE"
BODY_TYPE"PLUMBING"
CDS_LIB"mstr_standard";
"B \NAC \NWC"1;
"S \NAC"
BN"11"158;
%"TAP"
"6","(-3150,3800)","0","mstr_standard","I130";
;
HDL_TAP"TRUE"
BODY_TYPE"PLUMBING"
CDS_LIB"mstr_standard";
"B \NAC \NWC"10;
"S \NAC"
BN"1"32;
%"TAP"
"6","(-3150,3750)","0","mstr_standard","I133";
;
HDL_TAP"TRUE"
BODY_TYPE"PLUMBING"
CDS_LIB"mstr_standard";
"B \NAC \NWC"10;
"S \NAC"
BN"0"49;
%"TAP"
"6","(-3150,3700)","0","mstr_standard","I134";
;
HDL_TAP"TRUE"
BODY_TYPE"PLUMBING"
CDS_LIB"mstr_standard";
"B \NAC \NWC"11;
"S \NAC"
BN"1"48;
%"TAP"
"6","(-3150,3650)","0","mstr_standard","I135";
;
HDL_TAP"TRUE"
BODY_TYPE"PLUMBING"
CDS_LIB"mstr_standard";
"B \NAC \NWC"11;
"S \NAC"
BN"0"47;
%"TAP"
"6","(-3150,2700)","0","mstr_standard","I138";
;
HDL_TAP"TRUE"
BODY_TYPE"PLUMBING"
CDS_LIB"mstr_standard";
"B \NAC \NWC"12;
"S \NAC"
BN"7"51;
%"TAP"
"6","(-3150,2650)","0","mstr_standard","I139";
;
HDL_TAP"TRUE"
BODY_TYPE"PLUMBING"
CDS_LIB"mstr_standard";
"B \NAC \NWC"12;
"S \NAC"
BN"6"39;
%"TAP"
"6","(700,4650)","2","mstr_standard","I14";
;
HDL_TAP"TRUE"
BODY_TYPE"PLUMBING"
CDS_LIB"mstr_standard";
"B \NAC \NWC"1;
"S \NAC"
BN"12"160;
%"TAP"
"6","(-3150,2600)","0","mstr_standard","I140";
;
HDL_TAP"TRUE"
BODY_TYPE"PLUMBING"
CDS_LIB"mstr_standard";
"B \NAC \NWC"12;
"S \NAC"
BN"5"40;
%"TAP"
"6","(-3150,2550)","0","mstr_standard","I141";
;
HDL_TAP"TRUE"
BODY_TYPE"PLUMBING"
CDS_LIB"mstr_standard";
"B \NAC \NWC"12;
"S \NAC"
BN"4"41;
%"TAP"
"6","(-3150,2500)","0","mstr_standard","I142";
;
HDL_TAP"TRUE"
BODY_TYPE"PLUMBING"
CDS_LIB"mstr_standard";
"B \NAC \NWC"12;
"S \NAC"
BN"3"42;
%"TAP"
"6","(-3150,2450)","0","mstr_standard","I143";
;
HDL_TAP"TRUE"
BODY_TYPE"PLUMBING"
CDS_LIB"mstr_standard";
"B \NAC \NWC"12;
"S \NAC"
BN"2"43;
%"TAP"
"6","(-3150,2400)","0","mstr_standard","I144";
;
HDL_TAP"TRUE"
BODY_TYPE"PLUMBING"
CDS_LIB"mstr_standard";
"B \NAC \NWC"12;
"S \NAC"
BN"1"44;
%"TAP"
"6","(-3150,2350)","0","mstr_standard","I145";
;
HDL_TAP"TRUE"
BODY_TYPE"PLUMBING"
CDS_LIB"mstr_standard";
"B \NAC \NWC"12;
"S \NAC"
BN"0"45;
%"TAP"
"6","(700,4750)","2","mstr_standard","I15";
;
HDL_TAP"TRUE"
BODY_TYPE"PLUMBING"
CDS_LIB"mstr_standard";
"B \NAC \NWC"1;
"S \NAC"
BN"13"162;
%"TAP"
"6","(-3150,3550)","0","mstr_standard","I152";
;
HDL_TAP"TRUE"
BODY_TYPE"PLUMBING"
CDS_LIB"mstr_standard";
"B \NAC \NWC"6;
"S \NAC"
BN"3"57;
%"TAP"
"6","(-3150,3450)","0","mstr_standard","I153";
;
HDL_TAP"TRUE"
BODY_TYPE"PLUMBING"
CDS_LIB"mstr_standard";
"B \NAC \NWC"6;
"S \NAC"
BN"2"56;
%"TAP"
"6","(-3350,3500)","0","mstr_standard","I154";
;
HDL_TAP"TRUE"
BODY_TYPE"PLUMBING"
CDS_LIB"mstr_standard";
"B \NAC \NWC"5;
"S \NAC"
BN"3"58;
%"TAP"
"6","(-3350,3400)","0","mstr_standard","I155";
;
HDL_TAP"TRUE"
BODY_TYPE"PLUMBING"
CDS_LIB"mstr_standard";
"B \NAC \NWC"5;
"S \NAC"
BN"2"59;
%"TAP"
"6","(-3150,3250)","0","mstr_standard","I158";
;
HDL_TAP"TRUE"
BODY_TYPE"PLUMBING"
CDS_LIB"mstr_standard";
"B \NAC \NWC"8;
"S \NAC"
BN"7"33;
%"TAP"
"6","(-3150,3200)","0","mstr_standard","I159";
;
HDL_TAP"TRUE"
BODY_TYPE"PLUMBING"
CDS_LIB"mstr_standard";
"B \NAC \NWC"8;
"S \NAC"
BN"6"34;
%"PVDDQ_DEF"
"1","(-1150,2475)","0","mstr_symbols","I16";
;
HDL_POWER"PVDDQ_DEF"
ROOM"DDR4_CH_C"
BODY_TYPE"PLUMBING"
CDS_LIB"mstr_symbols"
BOM_COST"MEM"
VOLTAGE"1.2V";
"G\NAC"13;
%"TAP"
"6","(-3150,3150)","0","mstr_standard","I160";
;
HDL_TAP"TRUE"
BODY_TYPE"PLUMBING"
CDS_LIB"mstr_standard";
"B \NAC \NWC"8;
"S \NAC"
BN"5"35;
%"TAP"
"6","(-3150,3100)","0","mstr_standard","I161";
;
HDL_TAP"TRUE"
BODY_TYPE"PLUMBING"
CDS_LIB"mstr_standard";
"B \NAC \NWC"8;
"S \NAC"
BN"4"54;
%"TAP"
"6","(-3150,3000)","0","mstr_standard","I165";
;
HDL_TAP"TRUE"
BODY_TYPE"PLUMBING"
CDS_LIB"mstr_standard";
"B \NAC \NWC"7;
"S \NAC"
BN"3"46;
%"TAP"
"6","(-3150,2950)","0","mstr_standard","I166";
;
HDL_TAP"TRUE"
BODY_TYPE"PLUMBING"
CDS_LIB"mstr_standard";
"B \NAC \NWC"7;
"S \NAC"
BN"2"55;
%"TAP"
"6","(-3150,2850)","0","mstr_standard","I167";
;
HDL_TAP"TRUE"
BODY_TYPE"PLUMBING"
CDS_LIB"mstr_standard";
"B \NAC \NWC"9;
"S \NAC"
BN"3"53;
%"TAP"
"6","(-3150,2800)","0","mstr_standard","I168";
;
HDL_TAP"TRUE"
BODY_TYPE"PLUMBING"
CDS_LIB"mstr_standard";
"B \NAC \NWC"9;
"S \NAC"
BN"2"52;
%"PVTT_DEF"
"1","(-900,2600)","0","mstr_symbols","I17";
;
HDL_POWER"PVTT_DEF"
ROOM"DDR4_CH_C"
BODY_TYPE"PLUMBING"
CDS_LIB"mstr_symbols"
BOM_COST"MEM"
VOLTAGE"0.6V";
"G\NAC"14;
%"SCONN288_H44441003"
"4","(-50,1900)","0","mstr_sconn","I170";
;
CDS_SEC"4"
ROOM"DDR4_CH_F1"
CDS_LOCATION"J6L1"
SEC"4"
SEC_TYPE"PIP"
CDS_LIB"mstr_sconn"
BOM_COST"MEM"
PACK_TYPE"PIP"
MATERIAL"SCONN"
PART_NUMBER"H44441-003"
LOCATION"J6L1";
"VDD<0>"
$PN"236"13;
"VDD<6>"
$PN"220"13;
"VDD<10>"
$PN"209"13;
"VDD<13>"
$PN"92"13;
"VDD<16>"
$PN"85"13;
"VDD<19>"
$PN"76"13;
"VDD<23>"
$PN"64"13;
"VDD<25>"
$PN"59"13;
"VTT<0>"
$PN"221"14;
"12V<1>"
$PN"1"20;
"12V<0>"
$PN"145"20;
"VDD<24>"
$PN"61"13;
"VDD<22>"
$PN"67"13;
"VDD<21>"
$PN"70"13;
"VDD<20>"
$PN"73"13;
"VDD<18>"
$PN"80"13;
"VDD<17>"
$PN"83"13;
"VDD<15>"
$PN"88"13;
"VDD<14>"
$PN"90"13;
"VDD<12>"
$PN"204"13;
"VDD<11>"
$PN"206"13;
"VDD<9>"
$PN"212"13;
"VDD<8>"
$PN"215"13;
"VDD<7>"
$PN"217"13;
"VDD<5>"
$PN"223"13;
"VDD<4>"
$PN"226"13;
"VDD<3>"
$PN"229"13;
"VDD<2>"
$PN"231"13;
"VDD<1>"
$PN"233"13;
"VPP<4>"
$PN"142"17;
"VPP<3>"
$PN"143"17;
"VPP<2>"
$PN"288"17;
"VPP<1>"
$PN"286"17;
"VPP<0>"
$PN"287"17;
"VTT<1>"
$PN"77"14;
%"GND"
"1","(2500,1250)","2","mstr_symbols","I171";
;
HDL_POWER"GND"
ROOM"DDR4_CH_C"
BODY_TYPE"PLUMBING"
BOM_COST"MEM"
CDS_LIB"mstr_symbols"
SIZE"1B"
VOLTAGE"0";
"A\NAC"15;
%"GND"
"1","(-4600,1150)","0","mstr_symbols","I178";
;
HDL_POWER"GND"
ROOM"DDR4_CH_C"
BODY_TYPE"PLUMBING"
SIZE"1B"
BOM_COST"MEM"
CDS_LIB"mstr_symbols"
VOLTAGE"0";
"A\NAC"16;
%"CAP_A"
"1","(-4600,1400)","2","dev_discrete","I179";
;
ROOM"DDR4_CH_F1"
$SEC"1"
CDS_SEC"1"
CDS_LIB"dev_discrete"
BOM_COST"MEM"
CDS_LOCATION"C4A5"
MATERIAL"X7R"
VOLTAGE"25V"
PACK_TYPE"0402V"
TOLERANCE"10%"
VALUE"0.01UF"
PART_NUMBER"A36096-045"
LOCATION"C4A5";
"B"
$PN"2"16;
"A"
$PN"1"22;
%"PVPP_DEF"
"1","(-750,2900)","0","mstr_symbols","I180";
;
HDL_POWER"PVPP_DEF"
ROOM"DDR4_CH_C"
BODY_TYPE"PLUMBING"
CDS_LIB"mstr_symbols"
BOM_COST"MEM"
VOLTAGE"2.5V";
"G\NAC"17;
%"PVPP_DEF"
"1","(-5200,2100)","0","mstr_symbols","I181";
;
HDL_POWER"PVPP_DEF"
ROOM"DDR4_CH_C"
BODY_TYPE"PLUMBING"
CDS_LIB"mstr_symbols"
BOM_COST"MEM"
VOLTAGE"2.5V";
"G\NAC"18;
%"GND"
"1","(-5200,1750)","0","mstr_symbols","I186";
;
HDL_POWER"GND"
ROOM"DDR4_CH_C"
BODY_TYPE"PLUMBING"
CDS_LIB"mstr_symbols"
BOM_COST"MEM"
SIZE"1B"
VOLTAGE"0";
"A\NAC"19;
%"P12V_NVDIMM_DEF"
"1","(650,2975)","0","mstr_symbols","I187";
;
HDL_POWER"P12V_NVDIMM_DEF"
BODY_TYPE"PLUMBING"
CDS_LIB"mstr_symbols"
VOLTAGE"12.0";
"G\NAC"20;
%"TAP"
"6","(900,4500)","2","mstr_standard","I19";
;
HDL_TAP"TRUE"
BODY_TYPE"PLUMBING"
CDS_LIB"mstr_standard";
"B \NAC \NWC"2;
"S \NAC"
BN"11"157;
%"TAP"
"6","(900,4400)","2","mstr_standard","I20";
;
HDL_TAP"TRUE"
BODY_TYPE"PLUMBING"
CDS_LIB"mstr_standard";
"B \NAC \NWC"2;
"S \NAC"
BN"10"155;
%"TAP"
"6","(900,4300)","2","mstr_standard","I21";
;
HDL_TAP"TRUE"
BODY_TYPE"PLUMBING"
CDS_LIB"mstr_standard";
"B \NAC \NWC"2;
"S \NAC"
BN"9"174;
%"TAP"
"6","(900,4200)","2","mstr_standard","I22";
;
HDL_TAP"TRUE"
BODY_TYPE"PLUMBING"
CDS_LIB"mstr_standard";
"B \NAC \NWC"2;
"S \NAC"
BN"8"172;
%"TAP"
"6","(900,4100)","2","mstr_standard","I23";
;
HDL_TAP"TRUE"
BODY_TYPE"PLUMBING"
CDS_LIB"mstr_standard";
"B \NAC \NWC"2;
"S \NAC"
BN"7"170;
%"TAP"
"6","(700,4450)","2","mstr_standard","I24";
;
HDL_TAP"TRUE"
BODY_TYPE"PLUMBING"
CDS_LIB"mstr_standard";
"B \NAC \NWC"1;
"S \NAC"
BN"10"156;
%"TAP"
"6","(700,4350)","2","mstr_standard","I25";
;
HDL_TAP"TRUE"
BODY_TYPE"PLUMBING"
CDS_LIB"mstr_standard";
"B \NAC \NWC"1;
"S \NAC"
BN"9"175;
%"TAP"
"6","(700,4050)","2","mstr_standard","I26";
;
HDL_TAP"TRUE"
BODY_TYPE"PLUMBING"
CDS_LIB"mstr_standard";
"B \NAC \NWC"1;
"S \NAC"
BN"6"154;
%"TAP"
"6","(700,4150)","2","mstr_standard","I27";
;
HDL_TAP"TRUE"
BODY_TYPE"PLUMBING"
CDS_LIB"mstr_standard";
"B \NAC \NWC"1;
"S \NAC"
BN"7"171;
%"TAP"
"6","(700,4250)","2","mstr_standard","I28";
;
HDL_TAP"TRUE"
BODY_TYPE"PLUMBING"
CDS_LIB"mstr_standard";
"B \NAC \NWC"1;
"S \NAC"
BN"8"173;
%"TAP"
"6","(900,4000)","2","mstr_standard","I29";
;
HDL_TAP"TRUE"
BODY_TYPE"PLUMBING"
CDS_LIB"mstr_standard";
"B \NAC \NWC"2;
"S \NAC"
BN"6"153;
%"TAP"
"6","(900,5100)","2","mstr_standard","I3";
;
HDL_TAP"TRUE"
BODY_TYPE"PLUMBING"
CDS_LIB"mstr_standard";
"B \NAC \NWC"2;
"S \NAC"
BN"17"169;
%"TAP"
"6","(900,3900)","2","mstr_standard","I30";
;
HDL_TAP"TRUE"
BODY_TYPE"PLUMBING"
CDS_LIB"mstr_standard";
"B \NAC \NWC"2;
"S \NAC"
BN"5"151;
%"TAP"
"6","(900,3800)","2","mstr_standard","I31";
;
HDL_TAP"TRUE"
BODY_TYPE"PLUMBING"
CDS_LIB"mstr_standard";
"B \NAC \NWC"2;
"S \NAC"
BN"4"149;
%"TAP"
"6","(900,3700)","2","mstr_standard","I32";
;
HDL_TAP"TRUE"
BODY_TYPE"PLUMBING"
CDS_LIB"mstr_standard";
"B \NAC \NWC"2;
"S \NAC"
BN"3"147;
%"TAP"
"6","(900,3600)","2","mstr_standard","I33";
;
HDL_TAP"TRUE"
BODY_TYPE"PLUMBING"
CDS_LIB"mstr_standard";
"B \NAC \NWC"2;
"S \NAC"
BN"2"145;
%"TAP"
"6","(700,3950)","2","mstr_standard","I34";
;
HDL_TAP"TRUE"
BODY_TYPE"PLUMBING"
CDS_LIB"mstr_standard";
"B \NAC \NWC"1;
"S \NAC"
BN"5"152;
%"TAP"
"6","(700,3850)","2","mstr_standard","I35";
;
HDL_TAP"TRUE"
BODY_TYPE"PLUMBING"
CDS_LIB"mstr_standard";
"B \NAC \NWC"1;
"S \NAC"
BN"4"150;
%"TAP"
"6","(700,3650)","2","mstr_standard","I36";
;
HDL_TAP"TRUE"
BODY_TYPE"PLUMBING"
CDS_LIB"mstr_standard";
"B \NAC \NWC"1;
"S \NAC"
BN"2"146;
%"TAP"
"6","(700,3550)","2","mstr_standard","I37";
;
HDL_TAP"TRUE"
BODY_TYPE"PLUMBING"
CDS_LIB"mstr_standard";
"B \NAC \NWC"1;
"S \NAC"
BN"1"144;
%"TAP"
"6","(700,3750)","2","mstr_standard","I38";
;
HDL_TAP"TRUE"
BODY_TYPE"PLUMBING"
CDS_LIB"mstr_standard";
"B \NAC \NWC"1;
"S \NAC"
BN"3"148;
%"TAP"
"6","(900,3400)","2","mstr_standard","I39";
;
HDL_TAP"TRUE"
BODY_TYPE"PLUMBING"
CDS_LIB"mstr_standard";
"B \NAC \NWC"2;
"S \NAC"
BN"0"141;
%"TAP"
"6","(700,5150)","2","mstr_standard","I4";
;
HDL_TAP"TRUE"
BODY_TYPE"PLUMBING"
CDS_LIB"mstr_standard";
"B \NAC \NWC"1;
"S \NAC"
BN"17"176;
%"TAP"
"6","(900,3500)","2","mstr_standard","I40";
;
HDL_TAP"TRUE"
BODY_TYPE"PLUMBING"
CDS_LIB"mstr_standard";
"B \NAC \NWC"2;
"S \NAC"
BN"1"143;
%"TAP"
"6","(700,3450)","2","mstr_standard","I41";
;
HDL_TAP"TRUE"
BODY_TYPE"PLUMBING"
CDS_LIB"mstr_standard";
"B \NAC \NWC"1;
"S \NAC"
BN"0"142;
%"SCONN288_H44441003"
"3","(1800,2550)","0","mstr_sconn","I43";
;
CDS_SEC"3"
ROOM"DDR4_CH_F1"
CDS_LOCATION"J6L1"
SEC"3"
SEC_TYPE"PIP"
CDS_LIB"mstr_sconn"
BOM_COST"MEM"
PACK_TYPE"PIP"
MATERIAL"SCONN"
PART_NUMBER"H44441-003"
LOCATION"J6L1";
"VSS<46>"
$PN"147"15;
"VSS<45>"
$PN"149"15;
"VSS<87>"
$PN"15"21;
"VSS<86>"
$PN"17"21;
"VSS<85>"
$PN"20"21;
"VSS<84>"
$PN"22"21;
"VSS<83>"
$PN"24"21;
"VSS<82>"
$PN"26"21;
"VSS<81>"
$PN"28"21;
"VSS<80>"
$PN"31"21;
"VSS<79>"
$PN"33"21;
"VSS<78>"
$PN"35"21;
"VSS<77>"
$PN"37"21;
"VSS<76>"
$PN"39"21;
"VSS<75>"
$PN"42"21;
"VSS<74>"
$PN"44"21;
"VSS<73>"
$PN"46"21;
"VSS<72>"
$PN"48"21;
"VSS<71>"
$PN"50"21;
"VSS<70>"
$PN"53"21;
"VSS<69>"
$PN"55"21;
"VSS<68>"
$PN"57"21;
"VSS<67>"
$PN"94"21;
"VSS<66>"
$PN"96"21;
"VSS<65>"
$PN"98"21;
"VSS<64>"
$PN"101"21;
"VSS<63>"
$PN"103"21;
"VSS<62>"
$PN"105"21;
"VSS<61>"
$PN"107"21;
"VSS<60>"
$PN"109"21;
"VSS<59>"
$PN"112"21;
"VSS<58>"
$PN"114"21;
"VSS<57>"
$PN"116"21;
"VSS<56>"
$PN"118"21;
"VSS<55>"
$PN"120"21;
"VSS<54>"
$PN"123"21;
"VSS<53>"
$PN"125"21;
"VSS<52>"
$PN"127"21;
"VSS<51>"
$PN"129"21;
"VSS<50>"
$PN"131"21;
"VSS<49>"
$PN"134"21;
"VSS<48>"
$PN"136"21;
"VSS<47>"
$PN"138"21;
"VSS<44>"
$PN"151"15;
"VSS<43>"
$PN"154"15;
"VSS<42>"
$PN"156"15;
"VSS<41>"
$PN"158"15;
"VSS<40>"
$PN"160"15;
"VSS<39>"
$PN"162"15;
"VSS<38>"
$PN"165"15;
"VSS<37>"
$PN"167"15;
"VSS<36>"
$PN"169"15;
"VSS<35>"
$PN"171"15;
"VSS<34>"
$PN"173"15;
"VSS<33>"
$PN"176"15;
"VSS<32>"
$PN"178"15;
"VSS<31>"
$PN"180"15;
"VSS<30>"
$PN"182"15;
"VSS<29>"
$PN"184"15;
"VSS<28>"
$PN"187"15;
"VSS<27>"
$PN"189"15;
"VSS<26>"
$PN"191"15;
"VSS<25>"
$PN"193"15;
"VSS<24>"
$PN"195"15;
"VSS<23>"
$PN"198"15;
"VSS<22>"
$PN"200"15;
"VSS<21>"
$PN"202"15;
"VSS<20>"
$PN"239"15;
"VSS<19>"
$PN"241"15;
"VSS<18>"
$PN"243"15;
"VSS<17>"
$PN"246"15;
"VSS<16>"
$PN"248"15;
"VSS<15>"
$PN"250"15;
"VSS<14>"
$PN"252"15;
"VSS<13>"
$PN"254"15;
"VSS<12>"
$PN"257"15;
"VSS<11>"
$PN"259"15;
"VSS<10>"
$PN"261"15;
"VSS<9>"
$PN"263"15;
"VSS<8>"
$PN"265"15;
"VSS<7>"
$PN"268"15;
"VSS<6>"
$PN"270"15;
"VSS<5>"
$PN"272"15;
"VSS<4>"
$PN"274"15;
"VSS<3>"
$PN"276"15;
"VSS<2>"
$PN"279"15;
"VSS<1>"
$PN"281"15;
"VSS<0>"
$PN"283"15;
"VSS<88>"
$PN"13"21;
"VSS<89>"
$PN"11"21;
"VSS<90>"
$PN"9"21;
"VSS<91>"
$PN"6"21;
"VSS<92>"
$PN"4"21;
"VSS<93>"
$PN"2"21;
%"GND"
"1","(1100,1250)","2","mstr_symbols","I44";
;
HDL_POWER"GND"
ROOM"DDR4_CH_C"
BODY_TYPE"PLUMBING"
BOM_COST"MEM"
SIZE"1B"
CDS_LIB"mstr_symbols"
VOLTAGE"0";
"A\NAC"21;
%"TAP"
"6","(-1650,4650)","2","mstr_standard","I46";
;
HDL_TAP"TRUE"
BODY_TYPE"PLUMBING"
CDS_LIB"mstr_standard";
"B \NAC \NWC"4;
"S \NAC"
BN"61"140;
%"TAP"
"6","(-1650,4600)","2","mstr_standard","I47";
;
HDL_TAP"TRUE"
BODY_TYPE"PLUMBING"
CDS_LIB"mstr_standard";
"B \NAC \NWC"4;
"S \NAC"
BN"60"127;
%"TAP"
"6","(-1650,4700)","2","mstr_standard","I48";
;
HDL_TAP"TRUE"
BODY_TYPE"PLUMBING"
CDS_LIB"mstr_standard";
"B \NAC \NWC"4;
"S \NAC"
BN"62"139;
%"TAP"
"6","(-1650,4750)","2","mstr_standard","I49";
;
HDL_TAP"TRUE"
BODY_TYPE"PLUMBING"
CDS_LIB"mstr_standard";
"B \NAC \NWC"4;
"S \NAC"
BN"63"138;
%"TAP"
"6","(900,5000)","2","mstr_standard","I5";
;
HDL_TAP"TRUE"
BODY_TYPE"PLUMBING"
CDS_LIB"mstr_standard";
"B \NAC \NWC"2;
"S \NAC"
BN"16"167;
%"TAP"
"6","(-1650,4350)","2","mstr_standard","I50";
;
HDL_TAP"TRUE"
BODY_TYPE"PLUMBING"
CDS_LIB"mstr_standard";
"B \NAC \NWC"4;
"S \NAC"
BN"55"130;
%"TAP"
"6","(-1650,4400)","2","mstr_standard","I51";
;
HDL_TAP"TRUE"
BODY_TYPE"PLUMBING"
CDS_LIB"mstr_standard";
"B \NAC \NWC"4;
"S \NAC"
BN"56"129;
%"TAP"
"6","(-1650,4500)","2","mstr_standard","I52";
;
HDL_TAP"TRUE"
BODY_TYPE"PLUMBING"
CDS_LIB"mstr_standard";
"B \NAC \NWC"4;
"S \NAC"
BN"58"132;
%"TAP"
"6","(-1650,4450)","2","mstr_standard","I53";
;
HDL_TAP"TRUE"
BODY_TYPE"PLUMBING"
CDS_LIB"mstr_standard";
"B \NAC \NWC"4;
"S \NAC"
BN"57"131;
%"TAP"
"6","(-1650,4550)","2","mstr_standard","I54";
;
HDL_TAP"TRUE"
BODY_TYPE"PLUMBING"
CDS_LIB"mstr_standard";
"B \NAC \NWC"4;
"S \NAC"
BN"59"128;
%"TAP"
"6","(-1650,4100)","2","mstr_standard","I55";
;
HDL_TAP"TRUE"
BODY_TYPE"PLUMBING"
CDS_LIB"mstr_standard";
"B \NAC \NWC"4;
"S \NAC"
BN"50"137;
%"TAP"
"6","(-1650,4150)","2","mstr_standard","I56";
;
HDL_TAP"TRUE"
BODY_TYPE"PLUMBING"
CDS_LIB"mstr_standard";
"B \NAC \NWC"4;
"S \NAC"
BN"51"136;
%"TAP"
"6","(-1650,4200)","2","mstr_standard","I57";
;
HDL_TAP"TRUE"
BODY_TYPE"PLUMBING"
CDS_LIB"mstr_standard";
"B \NAC \NWC"4;
"S \NAC"
BN"52"135;
%"TAP"
"6","(-1650,4300)","2","mstr_standard","I58";
;
HDL_TAP"TRUE"
BODY_TYPE"PLUMBING"
CDS_LIB"mstr_standard";
"B \NAC \NWC"4;
"S \NAC"
BN"54"133;
%"TAP"
"6","(-1650,4250)","2","mstr_standard","I59";
;
HDL_TAP"TRUE"
BODY_TYPE"PLUMBING"
CDS_LIB"mstr_standard";
"B \NAC \NWC"4;
"S \NAC"
BN"53"134;
%"TAP"
"6","(900,4900)","2","mstr_standard","I6";
;
HDL_TAP"TRUE"
BODY_TYPE"PLUMBING"
CDS_LIB"mstr_standard";
"B \NAC \NWC"2;
"S \NAC"
BN"15"165;
%"TAP"
"6","(-1650,3800)","2","mstr_standard","I60";
;
HDL_TAP"TRUE"
BODY_TYPE"PLUMBING"
CDS_LIB"mstr_standard";
"B \NAC \NWC"4;
"S \NAC"
BN"44"105;
%"TAP"
"6","(-1650,3850)","2","mstr_standard","I61";
;
HDL_TAP"TRUE"
BODY_TYPE"PLUMBING"
CDS_LIB"mstr_standard";
"B \NAC \NWC"4;
"S \NAC"
BN"45"104;
%"TAP"
"6","(-1650,3900)","2","mstr_standard","I62";
;
HDL_TAP"TRUE"
BODY_TYPE"PLUMBING"
CDS_LIB"mstr_standard";
"B \NAC \NWC"4;
"S \NAC"
BN"46"103;
%"TAP"
"6","(-1650,4000)","2","mstr_standard","I63";
;
HDL_TAP"TRUE"
BODY_TYPE"PLUMBING"
CDS_LIB"mstr_standard";
"B \NAC \NWC"4;
"S \NAC"
BN"48"111;
%"TAP"
"6","(-1650,3950)","2","mstr_standard","I64";
;
HDL_TAP"TRUE"
BODY_TYPE"PLUMBING"
CDS_LIB"mstr_standard";
"B \NAC \NWC"4;
"S \NAC"
BN"47"112;
%"TAP"
"6","(-1650,4050)","2","mstr_standard","I65";
;
HDL_TAP"TRUE"
BODY_TYPE"PLUMBING"
CDS_LIB"mstr_standard";
"B \NAC \NWC"4;
"S \NAC"
BN"49"110;
%"SCONN288_H44441003"
"2","(0,4300)","0","mstr_sconn","I66";
;
CDS_SEC"2"
ROOM"DDR4_CH_F1"
CDS_LOCATION"J6L1"
SEC"2"
SEC_TYPE"PIP"
CDS_LIB"mstr_sconn"
BOM_COST"MEM"
PACK_TYPE"PIP"
MATERIAL"SCONN"
PART_NUMBER"H44441-003"
LOCATION"J6L1";
"DQS0N"
$PN"152"141;
"DQS0P"
$PN"153"142;
"DQS10N"
$PN"19"155;
"DQS10P"
$PN"18"156;
"DQS11N"
$PN"30"157;
"DQS11P"
$PN"29"158;
"DQS12N"
$PN"41"159;
"DQS12P"
$PN"40"160;
"DQS13N"
$PN"100"161;
"DQS13P"
$PN"99"162;
"DQS14N"
$PN"111"163;
"DQS14P"
$PN"110"164;
"DQS15N"
$PN"122"165;
"DQS15P"
$PN"121"166;
"DQS16N"
$PN"133"167;
"DQS16P"
$PN"132"168;
"DQS17N"
$PN"52"169;
"DQS17P"
$PN"51"176;
"DQS1N"
$PN"163"143;
"DQS1P"
$PN"164"144;
"DQS2N"
$PN"174"145;
"DQS2P"
$PN"175"146;
"DQS3N"
$PN"185"147;
"DQS3P"
$PN"186"148;
"DQS4N"
$PN"244"149;
"DQS4P"
$PN"245"150;
"DQS5N"
$PN"255"151;
"DQS5P"
$PN"256"152;
"DQS6N"
$PN"266"153;
"DQS6P"
$PN"267"154;
"DQS7N"
$PN"277"170;
"DQS7P"
$PN"278"171;
"DQS8N"
$PN"196"172;
"DQS8P"
$PN"197"173;
"DQS9N"
$PN"8"174;
"DQS9P"
$PN"7"175;
%"TAP"
"6","(-1650,3650)","2","mstr_standard","I67";
;
HDL_TAP"TRUE"
BODY_TYPE"PLUMBING"
CDS_LIB"mstr_standard";
"B \NAC \NWC"4;
"S \NAC"
BN"41"108;
%"TAP"
"6","(-1650,3550)","2","mstr_standard","I68";
;
HDL_TAP"TRUE"
BODY_TYPE"PLUMBING"
CDS_LIB"mstr_standard";
"B \NAC \NWC"4;
"S \NAC"
BN"39"93;
%"TAP"
"6","(-1650,3600)","2","mstr_standard","I69";
;
HDL_TAP"TRUE"
BODY_TYPE"PLUMBING"
CDS_LIB"mstr_standard";
"B \NAC \NWC"4;
"S \NAC"
BN"40"109;
%"TAP"
"6","(900,4800)","2","mstr_standard","I7";
;
HDL_TAP"TRUE"
BODY_TYPE"PLUMBING"
CDS_LIB"mstr_standard";
"B \NAC \NWC"2;
"S \NAC"
BN"14"163;
%"TAP"
"6","(-1650,3700)","2","mstr_standard","I70";
;
HDL_TAP"TRUE"
BODY_TYPE"PLUMBING"
CDS_LIB"mstr_standard";
"B \NAC \NWC"4;
"S \NAC"
BN"42"107;
%"TAP"
"6","(-1650,3750)","2","mstr_standard","I71";
;
HDL_TAP"TRUE"
BODY_TYPE"PLUMBING"
CDS_LIB"mstr_standard";
"B \NAC \NWC"4;
"S \NAC"
BN"43"106;
%"TAP"
"6","(-1650,3350)","2","mstr_standard","I72";
;
HDL_TAP"TRUE"
BODY_TYPE"PLUMBING"
CDS_LIB"mstr_standard";
"B \NAC \NWC"4;
"S \NAC"
BN"35"100;
%"TAP"
"6","(-1650,3300)","2","mstr_standard","I73";
;
HDL_TAP"TRUE"
BODY_TYPE"PLUMBING"
CDS_LIB"mstr_standard";
"B \NAC \NWC"4;
"S \NAC"
BN"34"95;
%"TAP"
"6","(-1650,3400)","2","mstr_standard","I74";
;
HDL_TAP"TRUE"
BODY_TYPE"PLUMBING"
CDS_LIB"mstr_standard";
"B \NAC \NWC"4;
"S \NAC"
BN"36"101;
%"TAP"
"6","(-1650,3450)","2","mstr_standard","I75";
;
HDL_TAP"TRUE"
BODY_TYPE"PLUMBING"
CDS_LIB"mstr_standard";
"B \NAC \NWC"4;
"S \NAC"
BN"37"94;
%"TAP"
"6","(-1650,3500)","2","mstr_standard","I76";
;
HDL_TAP"TRUE"
BODY_TYPE"PLUMBING"
CDS_LIB"mstr_standard";
"B \NAC \NWC"4;
"S \NAC"
BN"38"102;
%"TAP"
"6","(-1650,3100)","2","mstr_standard","I77";
;
HDL_TAP"TRUE"
BODY_TYPE"PLUMBING"
CDS_LIB"mstr_standard";
"B \NAC \NWC"4;
"S \NAC"
BN"30"99;
%"TAP"
"6","(-1650,3150)","2","mstr_standard","I78";
;
HDL_TAP"TRUE"
BODY_TYPE"PLUMBING"
CDS_LIB"mstr_standard";
"B \NAC \NWC"4;
"S \NAC"
BN"31"98;
%"TAP"
"6","(-1650,3050)","2","mstr_standard","I79";
;
HDL_TAP"TRUE"
BODY_TYPE"PLUMBING"
CDS_LIB"mstr_standard";
"B \NAC \NWC"4;
"S \NAC"
BN"29"83;
%"TAP"
"6","(900,4700)","2","mstr_standard","I8";
;
HDL_TAP"TRUE"
BODY_TYPE"PLUMBING"
CDS_LIB"mstr_standard";
"B \NAC \NWC"2;
"S \NAC"
BN"13"161;
%"TAP"
"6","(-1650,3200)","2","mstr_standard","I80";
;
HDL_TAP"TRUE"
BODY_TYPE"PLUMBING"
CDS_LIB"mstr_standard";
"B \NAC \NWC"4;
"S \NAC"
BN"32"97;
%"TAP"
"6","(-1650,3250)","2","mstr_standard","I81";
;
HDL_TAP"TRUE"
BODY_TYPE"PLUMBING"
CDS_LIB"mstr_standard";
"B \NAC \NWC"4;
"S \NAC"
BN"33"96;
%"TAP"
"6","(-1650,2850)","2","mstr_standard","I82";
;
HDL_TAP"TRUE"
BODY_TYPE"PLUMBING"
CDS_LIB"mstr_standard";
"B \NAC \NWC"4;
"S \NAC"
BN"25"85;
%"TAP"
"6","(-1650,2800)","2","mstr_standard","I83";
;
HDL_TAP"TRUE"
BODY_TYPE"PLUMBING"
CDS_LIB"mstr_standard";
"B \NAC \NWC"4;
"S \NAC"
BN"24"86;
%"TAP"
"6","(-1650,2900)","2","mstr_standard","I84";
;
HDL_TAP"TRUE"
BODY_TYPE"PLUMBING"
CDS_LIB"mstr_standard";
"B \NAC \NWC"4;
"S \NAC"
BN"26"92;
%"TAP"
"6","(-1650,3000)","2","mstr_standard","I85";
;
HDL_TAP"TRUE"
BODY_TYPE"PLUMBING"
CDS_LIB"mstr_standard";
"B \NAC \NWC"4;
"S \NAC"
BN"28"84;
%"TAP"
"6","(-1650,2950)","2","mstr_standard","I86";
;
HDL_TAP"TRUE"
BODY_TYPE"PLUMBING"
CDS_LIB"mstr_standard";
"B \NAC \NWC"4;
"S \NAC"
BN"27"91;
%"TAP"
"6","(-1650,2550)","2","mstr_standard","I87";
;
HDL_TAP"TRUE"
BODY_TYPE"PLUMBING"
CDS_LIB"mstr_standard";
"B \NAC \NWC"4;
"S \NAC"
BN"19"72;
%"TAP"
"6","(-1650,2600)","2","mstr_standard","I88";
;
HDL_TAP"TRUE"
BODY_TYPE"PLUMBING"
CDS_LIB"mstr_standard";
"B \NAC \NWC"4;
"S \NAC"
BN"20"90;
%"TAP"
"6","(-1650,2650)","2","mstr_standard","I89";
;
HDL_TAP"TRUE"
BODY_TYPE"PLUMBING"
CDS_LIB"mstr_standard";
"B \NAC \NWC"4;
"S \NAC"
BN"21"89;
%"TAP"
"6","(900,4600)","2","mstr_standard","I9";
;
HDL_TAP"TRUE"
BODY_TYPE"PLUMBING"
CDS_LIB"mstr_standard";
"B \NAC \NWC"2;
"S \NAC"
BN"12"159;
%"TAP"
"6","(-1650,2750)","2","mstr_standard","I90";
;
HDL_TAP"TRUE"
BODY_TYPE"PLUMBING"
CDS_LIB"mstr_standard";
"B \NAC \NWC"4;
"S \NAC"
BN"23"87;
%"TAP"
"6","(-1650,2700)","2","mstr_standard","I91";
;
HDL_TAP"TRUE"
BODY_TYPE"PLUMBING"
CDS_LIB"mstr_standard";
"B \NAC \NWC"4;
"S \NAC"
BN"22"88;
%"TAP"
"6","(-1650,2300)","2","mstr_standard","I92";
;
HDL_TAP"TRUE"
BODY_TYPE"PLUMBING"
CDS_LIB"mstr_standard";
"B \NAC \NWC"4;
"S \NAC"
BN"14"75;
%"TAP"
"6","(-1650,2350)","2","mstr_standard","I93";
;
HDL_TAP"TRUE"
BODY_TYPE"PLUMBING"
CDS_LIB"mstr_standard";
"B \NAC \NWC"4;
"S \NAC"
BN"15"80;
%"TAP"
"6","(-1650,2450)","2","mstr_standard","I94";
;
HDL_TAP"TRUE"
BODY_TYPE"PLUMBING"
CDS_LIB"mstr_standard";
"B \NAC \NWC"4;
"S \NAC"
BN"17"81;
%"TAP"
"6","(-1650,2400)","2","mstr_standard","I95";
;
HDL_TAP"TRUE"
BODY_TYPE"PLUMBING"
CDS_LIB"mstr_standard";
"B \NAC \NWC"4;
"S \NAC"
BN"16"74;
%"TAP"
"6","(-1650,2500)","2","mstr_standard","I96";
;
HDL_TAP"TRUE"
BODY_TYPE"PLUMBING"
CDS_LIB"mstr_standard";
"B \NAC \NWC"4;
"S \NAC"
BN"18"73;
%"TAP"
"6","(-1650,2250)","2","mstr_standard","I97";
;
HDL_TAP"TRUE"
BODY_TYPE"PLUMBING"
CDS_LIB"mstr_standard";
"B \NAC \NWC"4;
"S \NAC"
BN"13"76;
%"TAP"
"6","(-1650,2150)","2","mstr_standard","I98";
;
HDL_TAP"TRUE"
BODY_TYPE"PLUMBING"
CDS_LIB"mstr_standard";
"B \NAC \NWC"4;
"S \NAC"
BN"11"78;
%"TAP"
"6","(-1650,2200)","2","mstr_standard","I99";
;
HDL_TAP"TRUE"
BODY_TYPE"PLUMBING"
CDS_LIB"mstr_standard";
"B \NAC \NWC"4;
"S \NAC"
BN"12"77;
END.
